(kicad_pcb
	(version 20260206)
	(generator "pcbnew")
	(generator_version "10.0")
	(general
		(thickness 1.6)
		(legacy_teardrops no)
	)
	(paper "A4")
	(title_block
		(title "03242023_DA0F0TMBIJ0_F0T_Motherboard_J_brd_V01_OCP.brd")
		(comment 1 "Grand Teton / footprints 374-378 of 6105")
	)
	(layers
		(0 "F.Cu" signal "TOP")
		(4 "In1.Cu" signal "GND")
		(6 "In2.Cu" signal "IN1")
		(8 "In3.Cu" signal "GND1")
		(10 "In4.Cu" signal "IN2")
		(12 "In5.Cu" signal "GND2")
		(14 "In6.Cu" signal "IN3")
		(16 "In7.Cu" signal "GND3")
		(18 "In8.Cu" signal "VCC")
		(20 "In9.Cu" signal "VCC1")
		(22 "In10.Cu" signal "GND4")
		(24 "In11.Cu" signal "IN4")
		(26 "In12.Cu" signal "GND5")
		(28 "In13.Cu" signal "IN5")
		(30 "In14.Cu" signal "GND6")
		(32 "In15.Cu" signal "IN6")
		(34 "In16.Cu" signal "GND7")
		(2 "B.Cu" signal "BOTTOM")
		(9 "F.Adhes" user "F.Adhesive")
		(11 "B.Adhes" user "B.Adhesive")
		(13 "F.Paste" user "Package Geometry/Pastemask Top")
		(15 "B.Paste" user "Package Geometry/Pastemask Bottom")
		(5 "F.SilkS" user "Ref Des/Silkscreen Top")
		(7 "B.SilkS" user "Ref Des/Silkscreen Bottom")
		(1 "F.Mask" user "Board Geometry/Soldermask Top")
		(3 "B.Mask" user "Board Geometry/Soldermask Bottom")
		(17 "Dwgs.User" user "User.Drawings")
		(19 "Cmts.User" user "User.Comments")
		(21 "Eco1.User" user "User.Eco1")
		(23 "Eco2.User" user "User.Eco2")
		(25 "Edge.Cuts" user "Board Geometry/Outline")
		(27 "Margin" user)
		(31 "F.CrtYd" user "Package Geometry/Place Bound Top")
		(29 "B.CrtYd" user "Package Geometry/Place Bound Bottom")
		(35 "F.Fab" user "Ref Des/Assembly Top")
		(33 "B.Fab" user "Ref Des/Assembly Bottom")
	)
	(footprint ""
		(layer "F.Cu")
		(at 81.73847 -143.046704)
		(property "Reference" "R667"
			(at 0 0 0)
			(layer "F.SilkS")
			(hide yes)
			(effects
				(font
					(size 1.27 1.27)
				)
			)
		)
		(property "Value" ""
			(at 0 0 0)
			(layer "F.Fab")
			(effects
				(font
					(size 1.27 1.27)
				)
			)
		)
		(duplicate_pad_numbers_are_jumpers no)
		(fp_line
			(start -0.7874 -0.4064)
			(end 0.7874 -0.4064)
			(stroke
				(width 0.1524)
				(type default)
			)
			(layer "F.SilkS")
		)
		(fp_line
			(start -0.7874 0.4064)
			(end -0.7874 -0.4064)
			(stroke
				(width 0.1524)
				(type default)
			)
			(layer "F.SilkS")
		)
		(fp_line
			(start 0.7874 -0.4064)
			(end 0.7874 0.4064)
			(stroke
				(width 0.1524)
				(type default)
			)
			(layer "F.SilkS")
		)
		(fp_line
			(start 0.7874 0.4064)
			(end -0.7874 0.4064)
			(stroke
				(width 0.1524)
				(type default)
			)
			(layer "F.SilkS")
		)
		(fp_line
			(start -0.67945 -0.305054)
			(end -0.12065 -0.305054)
			(stroke
				(width 0.1)
				(type default)
			)
			(layer "F.Fab")
		)
		(fp_line
			(start -0.67945 0.3048)
			(end -0.67945 -0.305054)
			(stroke
				(width 0.1)
				(type default)
			)
			(layer "F.Fab")
		)
		(fp_line
			(start -0.12065 -0.305054)
			(end -0.12065 -0.2794)
			(stroke
				(width 0.1)
				(type default)
			)
			(layer "F.Fab")
		)
		(fp_line
			(start -0.12065 -0.2794)
			(end 0.12065 -0.2794)
			(stroke
				(width 0.1)
				(type default)
			)
			(layer "F.Fab")
		)
		(fp_line
			(start -0.12065 0.2794)
			(end -0.12065 0.3048)
			(stroke
				(width 0.1)
				(type default)
			)
			(layer "F.Fab")
		)
		(fp_line
			(start -0.12065 0.3048)
			(end -0.67945 0.3048)
			(stroke
				(width 0.1)
				(type default)
			)
			(layer "F.Fab")
		)
		(fp_line
			(start 0.120396 0.2794)
			(end -0.12065 0.2794)
			(stroke
				(width 0.1)
				(type default)
			)
			(layer "F.Fab")
		)
		(fp_line
			(start 0.120396 0.3048)
			(end 0.120396 0.2794)
			(stroke
				(width 0.1)
				(type default)
			)
			(layer "F.Fab")
		)
		(fp_line
			(start 0.12065 -0.3048)
			(end 0.67945 -0.3048)
			(stroke
				(width 0.1)
				(type default)
			)
			(layer "F.Fab")
		)
		(fp_line
			(start 0.12065 -0.2794)
			(end 0.12065 -0.3048)
			(stroke
				(width 0.1)
				(type default)
			)
			(layer "F.Fab")
		)
		(fp_line
			(start 0.67945 -0.3048)
			(end 0.67945 0.3048)
			(stroke
				(width 0.1)
				(type default)
			)
			(layer "F.Fab")
		)
		(fp_line
			(start 0.67945 0.3048)
			(end 0.120396 0.3048)
			(stroke
				(width 0.1)
				(type default)
			)
			(layer "F.Fab")
		)
		(pad "1" smd circle
			(at -0.40005 0)
			(size 0 0)
			(layers "F.Cu" "F.Mask" "F.Paste")
			(net "I3C_SPD_DDREFGH_CPU1_R_SCL")
		)
		(pad "2" smd circle
			(at 0.40005 0)
			(size 0 0)
			(layers "F.Cu" "F.Mask" "F.Paste")
			(net "I3C_SPD_DDREFGH_CPU1_LVC1_R_SCL")
		)
	)
	(footprint ""
		(layer "F.Cu")
		(at 125.48108 -106.238548 -90)
		(property "Reference" "R4049"
			(at 0 0 270)
			(layer "F.SilkS")
			(hide yes)
			(effects
				(font
					(size 1.27 1.27)
				)
			)
		)
		(property "Value" ""
			(at 0 0 270)
			(layer "F.Fab")
			(effects
				(font
					(size 1.27 1.27)
				)
			)
		)
		(duplicate_pad_numbers_are_jumpers no)
		(fp_line
			(start -0.7874 0.4064)
			(end -0.7874 -0.4064)
			(stroke
				(width 0.1524)
				(type default)
			)
			(layer "F.SilkS")
		)
		(fp_line
			(start 0.7874 0.4064)
			(end -0.7874 0.4064)
			(stroke
				(width 0.1524)
				(type default)
			)
			(layer "F.SilkS")
		)
		(fp_line
			(start -0.7874 -0.4064)
			(end 0.7874 -0.4064)
			(stroke
				(width 0.1524)
				(type default)
			)
			(layer "F.SilkS")
		)
		(fp_line
			(start 0.7874 -0.4064)
			(end 0.7874 0.4064)
			(stroke
				(width 0.1524)
				(type default)
			)
			(layer "F.SilkS")
		)
		(fp_line
			(start -0.67945 0.3048)
			(end -0.67945 -0.305054)
			(stroke
				(width 0.1)
				(type default)
			)
			(layer "F.Fab")
		)
		(fp_line
			(start -0.12065 0.3048)
			(end -0.67945 0.3048)
			(stroke
				(width 0.1)
				(type default)
			)
			(layer "F.Fab")
		)
		(fp_line
			(start 0.120396 0.3048)
			(end 0.120396 0.2794)
			(stroke
				(width 0.1)
				(type default)
			)
			(layer "F.Fab")
		)
		(fp_line
			(start 0.67945 0.3048)
			(end 0.120396 0.3048)
			(stroke
				(width 0.1)
				(type default)
			)
			(layer "F.Fab")
		)
		(fp_line
			(start -0.12065 0.2794)
			(end -0.12065 0.3048)
			(stroke
				(width 0.1)
				(type default)
			)
			(layer "F.Fab")
		)
		(fp_line
			(start 0.120396 0.2794)
			(end -0.12065 0.2794)
			(stroke
				(width 0.1)
				(type default)
			)
			(layer "F.Fab")
		)
		(fp_line
			(start -0.12065 -0.2794)
			(end 0.12065 -0.2794)
			(stroke
				(width 0.1)
				(type default)
			)
			(layer "F.Fab")
		)
		(fp_line
			(start 0.12065 -0.2794)
			(end 0.12065 -0.3048)
			(stroke
				(width 0.1)
				(type default)
			)
			(layer "F.Fab")
		)
		(fp_line
			(start 0.12065 -0.3048)
			(end 0.67945 -0.3048)
			(stroke
				(width 0.1)
				(type default)
			)
			(layer "F.Fab")
		)
		(fp_line
			(start 0.67945 -0.3048)
			(end 0.67945 0.3048)
			(stroke
				(width 0.1)
				(type default)
			)
			(layer "F.Fab")
		)
		(fp_line
			(start -0.67945 -0.305054)
			(end -0.12065 -0.305054)
			(stroke
				(width 0.1)
				(type default)
			)
			(layer "F.Fab")
		)
		(fp_line
			(start -0.12065 -0.305054)
			(end -0.12065 -0.2794)
			(stroke
				(width 0.1)
				(type default)
			)
			(layer "F.Fab")
		)
		(pad "1" smd circle
			(at -0.40005 0 270)
			(size 0 0)
			(layers "F.Cu" "F.Mask" "F.Paste")
			(net "RST_CPU1_DRAM_GH_PLD_LVT3_R_N")
		)
		(pad "2" smd circle
			(at 0.40005 0 270)
			(size 0 0)
			(layers "F.Cu" "F.Mask" "F.Paste")
			(net "RST_CPU1_DRAM_GH_PLD_LVT3_N")
		)
	)
	(footprint ""
		(layer "F.Cu")
		(at 169.27195 -358.135936 -90)
		(property "Reference" "PC1367"
			(at 0 0 270)
			(layer "F.SilkS")
			(hide yes)
			(effects
				(font
					(size 1.27 1.27)
				)
			)
		)
		(property "Value" ""
			(at 0 0 270)
			(layer "F.Fab")
			(effects
				(font
					(size 1.27 1.27)
				)
			)
		)
		(duplicate_pad_numbers_are_jumpers no)
		(fp_line
			(start -0.7874 0.4064)
			(end -0.7874 -0.4064)
			(stroke
				(width 0.1524)
				(type default)
			)
			(layer "F.SilkS")
		)
		(fp_line
			(start 0.7874 0.4064)
			(end -0.7874 0.4064)
			(stroke
				(width 0.1524)
				(type default)
			)
			(layer "F.SilkS")
		)
		(fp_line
			(start -0.7874 -0.4064)
			(end 0.7874 -0.4064)
			(stroke
				(width 0.1524)
				(type default)
			)
			(layer "F.SilkS")
		)
		(fp_line
			(start 0.7874 -0.4064)
			(end 0.7874 0.4064)
			(stroke
				(width 0.1524)
				(type default)
			)
			(layer "F.SilkS")
		)
		(fp_line
			(start -0.67945 0.3048)
			(end -0.67945 -0.305054)
			(stroke
				(width 0.1)
				(type default)
			)
			(layer "F.Fab")
		)
		(fp_line
			(start -0.12065 0.3048)
			(end -0.67945 0.3048)
			(stroke
				(width 0.1)
				(type default)
			)
			(layer "F.Fab")
		)
		(fp_line
			(start 0.120396 0.3048)
			(end 0.120396 0.2794)
			(stroke
				(width 0.1)
				(type default)
			)
			(layer "F.Fab")
		)
		(fp_line
			(start 0.67945 0.3048)
			(end 0.120396 0.3048)
			(stroke
				(width 0.1)
				(type default)
			)
			(layer "F.Fab")
		)
		(fp_line
			(start -0.12065 0.2794)
			(end -0.12065 0.3048)
			(stroke
				(width 0.1)
				(type default)
			)
			(layer "F.Fab")
		)
		(fp_line
			(start 0.120396 0.2794)
			(end -0.12065 0.2794)
			(stroke
				(width 0.1)
				(type default)
			)
			(layer "F.Fab")
		)
		(fp_line
			(start -0.12065 -0.2794)
			(end 0.12065 -0.2794)
			(stroke
				(width 0.1)
				(type default)
			)
			(layer "F.Fab")
		)
		(fp_line
			(start 0.12065 -0.2794)
			(end 0.12065 -0.3048)
			(stroke
				(width 0.1)
				(type default)
			)
			(layer "F.Fab")
		)
		(fp_line
			(start 0.12065 -0.3048)
			(end 0.67945 -0.3048)
			(stroke
				(width 0.1)
				(type default)
			)
			(layer "F.Fab")
		)
		(fp_line
			(start 0.67945 -0.3048)
			(end 0.67945 0.3048)
			(stroke
				(width 0.1)
				(type default)
			)
			(layer "F.Fab")
		)
		(fp_line
			(start -0.67945 -0.305054)
			(end -0.12065 -0.305054)
			(stroke
				(width 0.1)
				(type default)
			)
			(layer "F.Fab")
		)
		(fp_line
			(start -0.12065 -0.305054)
			(end -0.12065 -0.2794)
			(stroke
				(width 0.1)
				(type default)
			)
			(layer "F.Fab")
		)
		(pad "1" smd circle
			(at -0.40005 0 270)
			(size 0 0)
			(layers "F.Cu" "F.Mask" "F.Paste")
			(net "GND")
		)
		(pad "2" smd circle
			(at 0.40005 0 270)
			(size 0 0)
			(layers "F.Cu" "F.Mask" "F.Paste")
			(net "PVCCIN_CPU1_VREF")
		)
	)
	(footprint ""
		(layer "F.Cu")
		(at 407.694384 -16.088614 90)
		(property "Reference" "C850"
			(at 0 0 90)
			(layer "F.SilkS")
			(hide yes)
			(effects
				(font
					(size 1.27 1.27)
				)
			)
		)
		(property "Value" ""
			(at 0 0 90)
			(layer "F.Fab")
			(effects
				(font
					(size 1.27 1.27)
				)
			)
		)
		(duplicate_pad_numbers_are_jumpers no)
		(fp_line
			(start 0.299974 -0.150114)
			(end 0.299974 0.150114)
			(stroke
				(width 0.1)
				(type default)
			)
			(layer "F.Fab")
		)
		(fp_line
			(start -0.299974 -0.150114)
			(end 0.299974 -0.150114)
			(stroke
				(width 0.1)
				(type default)
			)
			(layer "F.Fab")
		)
		(fp_line
			(start 0.299974 0.150114)
			(end -0.299974 0.150114)
			(stroke
				(width 0.1)
				(type default)
			)
			(layer "F.Fab")
		)
		(fp_line
			(start -0.299974 0.150114)
			(end -0.299974 -0.150114)
			(stroke
				(width 0.1)
				(type default)
			)
			(layer "F.Fab")
		)
		(pad "1" smd rect
			(at -0.2667 0 90)
			(size 0.3048 0.381)
			(layers "F.Cu" "F.Mask" "F.Paste")
			(net "P5E_CPU0_PE1_TX_C_DN<9>")
		)
		(pad "2" smd rect
			(at 0.2667 0 90)
			(size 0.3048 0.381)
			(layers "F.Cu" "F.Mask" "F.Paste")
			(net "P5E_CPU0_PE1_TX_DN<9>")
		)
	)
	(footprint ""
		(layer "F.Cu")
		(at 336.777076 -337.126326)
		(property "Reference" "PU8_P0_6"
			(at -1.222756 -6.773672 0)
			(unlocked yes)
			(layer "F.SilkS")
			(effects
				(font
					(size 0.7874 0.5842)
					(thickness 0.1524)
				)
				(justify left)
			)
		)
		(property "Value" ""
			(at 0 0 0)
			(layer "F.Fab")
			(effects
				(font
					(size 1.27 1.27)
				)
			)
		)
		(duplicate_pad_numbers_are_jumpers no)
		(fp_line
			(start -2.500122 -2.999994)
			(end -2.24409 -2.999994)
			(stroke
				(width 0.1524)
				(type default)
			)
			(layer "F.SilkS")
		)
		(fp_line
			(start -2.500122 -2.529078)
			(end -2.500122 -2.999994)
			(stroke
				(width 0.1524)
				(type default)
			)
			(layer "F.SilkS")
		)
		(fp_line
			(start -2.500122 0.6604)
			(end -2.500122 0.229108)
			(stroke
				(width 0.1524)
				(type default)
			)
			(layer "F.SilkS")
		)
		(fp_line
			(start -2.500122 2.999994)
			(end -2.500122 2.339594)
			(stroke
				(width 0.1524)
				(type default)
			)
			(layer "F.SilkS")
		)
		(fp_line
			(start -2.2987 2.999994)
			(end -2.500122 2.999994)
			(stroke
				(width 0.1524)
				(type default)
			)
			(layer "F.SilkS")
		)
		(fp_line
			(start 2.31394 -2.999994)
			(end 2.500122 -2.999994)
			(stroke
				(width 0.1524)
				(type default)
			)
			(layer "F.SilkS")
		)
		(fp_line
			(start 2.500122 -2.999994)
			(end 2.500122 -2.44348)
			(stroke
				(width 0.1524)
				(type default)
			)
			(layer "F.SilkS")
		)
		(fp_line
			(start 2.500122 2.339594)
			(end 2.500122 2.999994)
			(stroke
				(width 0.1524)
				(type default)
			)
			(layer "F.SilkS")
		)
		(fp_line
			(start 2.500122 2.999994)
			(end 2.2987 2.999994)
			(stroke
				(width 0.1524)
				(type default)
			)
			(layer "F.SilkS")
		)
		(fp_poly
			(pts
				(xy -2.21742 -3.606038) (xy -2.72542 -2.590038) (xy -3.23342 -3.606038)
			)
			(stroke
				(width 0)
				(type default)
			)
			(fill yes)
			(layer "F.SilkS")
		)
		(fp_line
			(start -2.500122 -2.999994)
			(end 2.500122 -2.999994)
			(stroke
				(width 0.1)
				(type default)
			)
			(layer "F.Fab")
		)
		(fp_line
			(start -2.500122 2.999994)
			(end -2.500122 -2.999994)
			(stroke
				(width 0.1)
				(type default)
			)
			(layer "F.Fab")
		)
		(fp_line
			(start 2.500122 -2.999994)
			(end 2.500122 2.999994)
			(stroke
				(width 0.1)
				(type default)
			)
			(layer "F.Fab")
		)
		(fp_line
			(start 2.500122 2.999994)
			(end -2.500122 2.999994)
			(stroke
				(width 0.1)
				(type default)
			)
			(layer "F.Fab")
		)
		(fp_poly
			(pts
				(xy -4.218432 -2.783078) (xy -4.218432 -1.767078) (xy -3.202432 -2.275078)
			)
			(stroke
				(width 0)
				(type default)
			)
			(fill yes)
			(layer "F.Fab")
		)
		(pad "1" smd rect
			(at -2.400046 -2.275078 90)
			(size 0.2286 0.6096)
			(layers "F.Cu" "F.Mask" "F.Paste")
			(net "PVCCIN_CPU0_VOS6")
		)
		(pad "2" smd rect
			(at -2.400046 -1.82499 90)
			(size 0.2286 0.6096)
			(layers "F.Cu" "F.Mask" "F.Paste")
			(net "GND")
		)
		(pad "3" smd rect
			(at -2.400046 -1.374902 90)
			(size 0.2286 0.6096)
			(layers "F.Cu" "F.Mask" "F.Paste")
			(net "PVCCIN_CPU0_VDD6")
		)
		(pad "4" smd rect
			(at -2.400046 -0.925068 90)
			(size 0.2286 0.6096)
			(layers "F.Cu" "F.Mask" "F.Paste")
			(net "PVCCIN_CPU0_PVCC")
		)
		(pad "5" smd rect
			(at -2.400046 -0.47498 90)
			(size 0.2286 0.6096)
			(layers "F.Cu" "F.Mask" "F.Paste")
			(net "GND")
		)
		(pad "6" smd rect
			(at -2.400046 -0.024892 90)
			(size 0.2286 0.6096)
			(layers "F.Cu" "F.Mask" "F.Paste")
			(net "Net_8559")
		)
		(pad "7_9-20_24" smd circle
			(at 0 1.150112 90)
			(size 0 0)
			(layers "F.Cu" "F.Mask" "F.Paste")
			(net "GND")
		)
		(pad "10_19" smd rect
			(at 0 2.899918 90)
			(size 0.6096 4.318)
			(layers "F.Cu" "F.Mask" "F.Paste")
			(net "SW_PVCCIN_CPU0_SW6")
		)
		(pad "25_29" smd rect
			(at 1.549908 -1.279906 270)
			(size 2.0574 2.3114)
			(layers "F.Cu" "F.Mask" "F.Paste")
			(net "SW_P12V_PVCCIN_CPU0_FLT")
		)
		(pad "30" smd rect
			(at 2.05994 -2.899918)
			(size 0.2286 0.6096)
			(layers "F.Cu" "F.Mask" "F.Paste")
			(net "SW_P12V_PVCCIN_CPU0_FLT")
		)
		(pad "31" smd rect
			(at 1.610106 -2.899918)
			(size 0.2286 0.6096)
			(layers "F.Cu" "F.Mask" "F.Paste")
			(net "Net_8560")
		)
		(pad "32" smd rect
			(at 1.160018 -2.899918)
			(size 0.2286 0.6096)
			(layers "F.Cu" "F.Mask" "F.Paste")
			(net "SW_PVCCIN_CPU0_BOOTR6")
		)
		(pad "33" smd rect
			(at 0.70993 -2.899918)
			(size 0.2286 0.6096)
			(layers "F.Cu" "F.Mask" "F.Paste")
			(net "SW_PVCCIN_CPU0_BOOT6")
		)
		(pad "34" smd rect
			(at 0.260096 -2.899918)
			(size 0.2286 0.6096)
			(layers "F.Cu" "F.Mask" "F.Paste")
			(net "PVCCIN_CPU0_PWM6")
		)
		(pad "35" smd rect
			(at -0.189992 -2.899918)
			(size 0.2286 0.6096)
			(layers "F.Cu" "F.Mask" "F.Paste")
			(net "PVCCIN_CPU0_VDD6")
		)
		(pad "36" smd rect
			(at -0.64008 -2.899918)
			(size 0.2286 0.6096)
			(layers "F.Cu" "F.Mask" "F.Paste")
			(net "PVCCIN_CPU0_ATSEN")
		)
		(pad "37" smd rect
			(at -1.089914 -2.899918)
			(size 0.2286 0.6096)
			(layers "F.Cu" "F.Mask" "F.Paste")
			(net "PVCCIN_CPU0_LSET6")
		)
		(pad "38" smd rect
			(at -1.540002 -2.899918)
			(size 0.2286 0.6096)
			(layers "F.Cu" "F.Mask" "F.Paste")
			(net "PVCCIN_CPU0_IMON6")
		)
		(pad "39" smd rect
			(at -1.99009 -2.899918)
			(size 0.2286 0.6096)
			(layers "F.Cu" "F.Mask" "F.Paste")
			(net "PVCCIN_CPU0_VREF")
		)
		(pad "40" smd rect
			(at -0.87503 -1.27508)
			(size 1.7526 1.9558)
			(layers "F.Cu" "F.Mask" "F.Paste")
			(net "GND")
		)
		(pad "41" smd rect
			(at -1.525016 0.249936 270)
			(size 0.3048 0.4572)
			(layers "F.Cu" "F.Mask" "F.Paste")
			(net "Net_8558")
		)
		(zone
			(layer "F.Cu")
			(hatch none 0.5)
			(connect_pads
				(clearance 0)
			)
			(min_thickness 0.25)
			(keepout
				(tracks not_allowed)
				(vias allowed)
				(pads allowed)
				(copperpour not_allowed)
				(footprints allowed)
			)
			(placement
				(enabled no)
				(sheetname "")
			)
			(fill
				(thermal_gap 0.5)
				(thermal_bridge_width 0.5)
				(island_removal_mode 0)
			)
			(polygon
				(pts
					(xy 334.974946 -338.816442) (xy 334.974946 -337.764628) (xy 334.73263 -337.764628) (xy 334.73263 -338.844128)
					(xy 334.94726 -338.844128)
				)
			)
		)
		(zone
			(layer "F.Cu")
			(hatch none 0.5)
			(connect_pads
				(clearance 0)
			)
			(min_thickness 0.25)
			(keepout
				(tracks not_allowed)
				(vias allowed)
				(pads allowed)
				(copperpour not_allowed)
				(footprints allowed)
			)
			(placement
				(enabled no)
				(sheetname "")
			)
			(fill
				(thermal_gap 0.5)
				(thermal_bridge_width 0.5)
				(island_removal_mode 0)
			)
			(polygon
				(pts
					(xy 334.276954 -334.126332) (xy 334.276954 -334.875632) (xy 339.277198 -334.875632) (xy 339.277198 -334.126332)
					(xy 338.986876 -334.126332) (xy 338.986876 -334.582008) (xy 334.567276 -334.582008) (xy 334.567276 -334.126332)
				)
			)
		)
	)
)
